FILE_TYPE = MACRO_DRAWING;
SET COLOR_WIRE YELLOW;
SET COLOR_PROP MONO;
SET COLOR_DOT WHITE;
SET COLOR_ARC YELLOW;
SET COLOR_BODY GREEN;
SET COLOR_NOTE MONO;
SET PROP_DISPLAY VALUE;
SET PAGE_NUMBER P6;
FORCEADD INTEL_CORP_BPAGE..1
(250 -50);
FORCEPROP 1 LAST CDS_CON_LAST_MODIFIED Fri Jun 16 17:47:57 2017
J 0
(-1175 275);
DISPLAY 1.595745 (-1175 275);
PAINT GREEN (-1175 275);
DISPLAY INVISIBLE (-1175 275);
FORCEPROP 1 LAST CUSTOM_TXT_CDS <CURRENT_DESIGN_SHEET> OF <TOTAL_DESIGN_SHEETS>
J 0
(-250 -25);
PAINT ORANGE (-250 -25);
FORCEPROP 1 LAST CUSTOM_TXT_CDS <CON_LAST_MODIFIED>
J 0
(-3750 50);
PAINT ORANGE (-3750 50);
FORCEPROP 2 LAST CUSTOM_TXT_CDS <XR_PAGE_TITLE>
J 0
(-7640 5200);
DISPLAY 0.638298 (-7640 5200);
PAINT PINK (-7640 5200);
DISPLAY INVISIBLE (-7640 5200);
FORCEPROP 1 LAST SCH_TITLE CLOCK BLOCK DIAGRAM
J 0
(-7700 0);
DISPLAY 1.212766 (-7700 0);
PAINT ORANGE (-7700 0);
FORCEPROP 2 LAST PAGE_BORDER TRUE
J 0
(-7640 5200);
PAINT PINK (-7640 5200);
DISPLAY INVISIBLE (-7640 5200);
FORCEPROP 2 LAST CDS_LIB mstr_symbols
J 0
(250 -50);
DISPLAY 1.595745 (250 -50);
PAINT ORANGE (250 -50);
DISPLAY INVISIBLE (250 -50);
FORCEPROP 1 LAST COMMENT_BODY TRUE
J 0
(262 -38);
DISPLAY 0.744681 (262 -38);
PAINT GREEN (262 -38);
DISPLAY INVISIBLE (262 -38);
FORCEPROP 2 LAST CDS_XR_PAGE_TITLE CR-6 : @BASEBOARD_FAB2_LIB.BASEBOARD_FAB2(SCH_1):PAGE6
J 0
(-7640 5200);
DISPLAY 0.638298 (-7640 5200);
PAINT PINK (-7640 5200);
DISPLAY INVISIBLE (-7640 5200);
FORCENOTE
$CDS_IMAGE|06_CLOCK TOPOLOGY_0.jpg|6250|4250
(-4200 2600) 0;
DISPLAY LEFT (-4200 2600);
QUIT
